FILE_TYPE=LIBRARY_PARTS;
primitive 'HCB1608KF-800T30-GP';
  pin
    '1':
      PIN_NUMBER='(1)';
      PIN_TYPE='ANALOG';
      NO_LOAD_CHECK='Both';
      NO_IO_CHECK='Both';
      NO_ASSERT_CHECK='TRUE';
      NO_DIR_CHECK='TRUE';
      ALLOW_CONNECT='TRUE';
    '2':
      PIN_NUMBER='(2)';
      PIN_TYPE='ANALOG';
      NO_LOAD_CHECK='Both';
      NO_IO_CHECK='Both';
      NO_ASSERT_CHECK='TRUE';
      NO_DIR_CHECK='TRUE';
      ALLOW_CONNECT='TRUE';
  end_pin;
  body
    PART_NAME='HCB1608KF-800T30-GP';
    BODY_NAME='HCB1608KF-800T30-GP';
    PHYS_DES_PREFIX='L';
    CLASS='DISCRETE';
  end_body;
end_primitive;

END.
